# S9S_MB_2U (Grand Teton) — schematic netlist excerpt (pin names and nets, part order shuffled) for the footprints in the layout excerpt that follows; sources: Cadence DE-HDL packaged netlist, KiCad conversion of 03242023_DA0F0TMBIJ0_F0T_Motherboard_J_brd_V01_OCP.brd

R4023  Q_RES  33.2 1% CHIP  pkg 0402LF  page 226 : A = H_CPU_CATERR_LVC2_R1_N ; B = H_CPU_CATERR_LVC2_R2_N
PC616_P0_2  Q_CAP  22UF 4V 20% X6S  pkg C0805  page 271 : A = PVCCFA_EHV_FIVRA_CPU0 ; B = GND
R71  Q_RES  10K 1% CHIP  pkg 0402LF  page 204 : A = P3V3_AUX ; B = FM_ME_BT_DONE

(kicad_pcb
	(version 20260206)
	(generator "pcbnew")
	(generator_version "10.0")
	(general
		(thickness 1.6)
		(legacy_teardrops no)
	)
	(paper "A4")
	(title_block
		(title "03242023_DA0F0TMBIJ0_F0T_Motherboard_J_brd_V01_OCP.brd")
		(comment 1 "Grand Teton / footprints 5190-5192 of 6105")
	)
	(layers
		(0 "F.Cu" signal "TOP")
		(4 "In1.Cu" signal "GND")
		(6 "In2.Cu" signal "IN1")
		(8 "In3.Cu" signal "GND1")
		(10 "In4.Cu" signal "IN2")
		(12 "In5.Cu" signal "GND2")
		(14 "In6.Cu" signal "IN3")
		(16 "In7.Cu" signal "GND3")
		(18 "In8.Cu" signal "VCC")
		(20 "In9.Cu" signal "VCC1")
		(22 "In10.Cu" signal "GND4")
		(24 "In11.Cu" signal "IN4")
		(26 "In12.Cu" signal "GND5")
		(28 "In13.Cu" signal "IN5")
		(30 "In14.Cu" signal "GND6")
		(32 "In15.Cu" signal "IN6")
		(34 "In16.Cu" signal "GND7")
		(2 "B.Cu" signal "BOTTOM")
		(9 "F.Adhes" user "F.Adhesive")
		(11 "B.Adhes" user "B.Adhesive")
		(13 "F.Paste" user "Package Geometry/Pastemask Top")
		(15 "B.Paste" user "Package Geometry/Pastemask Bottom")
		(5 "F.SilkS" user "Ref Des/Silkscreen Top")
		(7 "B.SilkS" user "Ref Des/Silkscreen Bottom")
		(1 "F.Mask" user "Board Geometry/Soldermask Top")
		(3 "B.Mask" user "Board Geometry/Soldermask Bottom")
		(17 "Dwgs.User" user "User.Drawings")
		(19 "Cmts.User" user "User.Comments")
		(21 "Eco1.User" user "User.Eco1")
		(23 "Eco2.User" user "User.Eco2")
		(25 "Edge.Cuts" user "Board Geometry/Outline")
		(27 "Margin" user)
		(31 "F.CrtYd" user "Package Geometry/Place Bound Top")
		(29 "B.CrtYd" user "Package Geometry/Place Bound Bottom")
		(35 "F.Fab" user "Ref Des/Assembly Top")
		(33 "B.Fab" user "Ref Des/Assembly Bottom")
	)
	(footprint ""
		(layer "B.Cu")
		(at 342.037416 -37.574728 -90)
		(property "Reference" "R71"
			(at 0 0 90)
			(layer "B.SilkS")
			(hide yes)
			(effects
				(font
					(size 1.27 1.27)
				)
				(justify mirror)
			)
		)
		(property "Value" ""
			(at 0 0 90)
			(layer "B.Fab")
			(effects
				(font
					(size 1.27 1.27)
				)
				(justify mirror)
			)
		)
		(duplicate_pad_numbers_are_jumpers no)
		(fp_line
			(start -0.7874 0.4064)
			(end 0.7874 0.4064)
			(stroke
				(width 0.1524)
				(type default)
			)
			(layer "B.SilkS")
		)
		(fp_line
			(start 0.7874 0.4064)
			(end 0.7874 -0.4064)
			(stroke
				(width 0.1524)
				(type default)
			)
			(layer "B.SilkS")
		)
		(fp_line
			(start -0.7874 -0.4064)
			(end -0.7874 0.4064)
			(stroke
				(width 0.1524)
				(type default)
			)
			(layer "B.SilkS")
		)
		(fp_line
			(start 0.7874 -0.4064)
			(end -0.7874 -0.4064)
			(stroke
				(width 0.1524)
				(type default)
			)
			(layer "B.SilkS")
		)
		(fp_line
			(start -0.67945 0.3048)
			(end -0.120396 0.3048)
			(stroke
				(width 0.1)
				(type default)
			)
			(layer "B.Fab")
		)
		(fp_line
			(start -0.120396 0.3048)
			(end -0.120396 0.2794)
			(stroke
				(width 0.1)
				(type default)
			)
			(layer "B.Fab")
		)
		(fp_line
			(start 0.12065 0.3048)
			(end 0.67945 0.3048)
			(stroke
				(width 0.1)
				(type default)
			)
			(layer "B.Fab")
		)
		(fp_line
			(start 0.67945 0.3048)
			(end 0.67945 -0.305054)
			(stroke
				(width 0.1)
				(type default)
			)
			(layer "B.Fab")
		)
		(fp_line
			(start -0.120396 0.2794)
			(end 0.12065 0.2794)
			(stroke
				(width 0.1)
				(type default)
			)
			(layer "B.Fab")
		)
		(fp_line
			(start 0.12065 0.2794)
			(end 0.12065 0.3048)
			(stroke
				(width 0.1)
				(type default)
			)
			(layer "B.Fab")
		)
		(fp_line
			(start -0.12065 -0.2794)
			(end -0.12065 -0.3048)
			(stroke
				(width 0.1)
				(type default)
			)
			(layer "B.Fab")
		)
		(fp_line
			(start 0.12065 -0.2794)
			(end -0.12065 -0.2794)
			(stroke
				(width 0.1)
				(type default)
			)
			(layer "B.Fab")
		)
		(fp_line
			(start -0.67945 -0.3048)
			(end -0.67945 0.3048)
			(stroke
				(width 0.1)
				(type default)
			)
			(layer "B.Fab")
		)
		(fp_line
			(start -0.12065 -0.3048)
			(end -0.67945 -0.3048)
			(stroke
				(width 0.1)
				(type default)
			)
			(layer "B.Fab")
		)
		(fp_line
			(start 0.12065 -0.305054)
			(end 0.12065 -0.2794)
			(stroke
				(width 0.1)
				(type default)
			)
			(layer "B.Fab")
		)
		(fp_line
			(start 0.67945 -0.305054)
			(end 0.12065 -0.305054)
			(stroke
				(width 0.1)
				(type default)
			)
			(layer "B.Fab")
		)
		(pad "1" smd circle
			(at 0.40005 0 90)
			(size 0 0)
			(layers "B.Cu" "B.Mask" "B.Paste")
			(net "P3V3_AUX")
		)
		(pad "2" smd circle
			(at -0.40005 0 90)
			(size 0 0)
			(layers "B.Cu" "B.Mask" "B.Paste")
			(net "FM_ME_BT_DONE")
		)
	)
	(footprint ""
		(layer "B.Cu")
		(at 295.130474 -354.163376 -90)
		(property "Reference" "PC616_P0_2"
			(at 0 0 90)
			(layer "B.SilkS")
			(hide yes)
			(effects
				(font
					(size 1.27 1.27)
				)
				(justify mirror)
			)
		)
		(property "Value" ""
			(at 0 0 90)
			(layer "B.Fab")
			(effects
				(font
					(size 1.27 1.27)
				)
				(justify mirror)
			)
		)
		(duplicate_pad_numbers_are_jumpers no)
		(fp_line
			(start -1.524 0.762)
			(end 1.524 0.762)
			(stroke
				(width 0.1524)
				(type default)
			)
			(layer "B.SilkS")
		)
		(fp_line
			(start 1.524 0.762)
			(end 1.524 -0.762)
			(stroke
				(width 0.1524)
				(type default)
			)
			(layer "B.SilkS")
		)
		(fp_line
			(start -1.524 -0.762)
			(end -1.524 0.762)
			(stroke
				(width 0.1524)
				(type default)
			)
			(layer "B.SilkS")
		)
		(fp_line
			(start 1.524 -0.762)
			(end -1.524 -0.762)
			(stroke
				(width 0.1524)
				(type default)
			)
			(layer "B.SilkS")
		)
		(fp_line
			(start -1.1049 0.724916)
			(end -1.1049 -0.724916)
			(stroke
				(width 0.1)
				(type default)
			)
			(layer "B.Fab")
		)
		(fp_line
			(start 1.1049 0.724916)
			(end -1.1049 0.724916)
			(stroke
				(width 0.1)
				(type default)
			)
			(layer "B.Fab")
		)
		(fp_line
			(start -1.1049 -0.724916)
			(end 1.1049 -0.724916)
			(stroke
				(width 0.1)
				(type default)
			)
			(layer "B.Fab")
		)
		(fp_line
			(start 1.1049 -0.724916)
			(end 1.1049 0.724916)
			(stroke
				(width 0.1)
				(type default)
			)
			(layer "B.Fab")
		)
		(pad "1" smd rect
			(at 0.889 0 270)
			(size 1.016 1.27)
			(layers "B.Cu" "B.Mask" "B.Paste")
			(net "PVCCFA_EHV_FIVRA_CPU0")
		)
		(pad "2" smd rect
			(at -0.889 0 270)
			(size 1.016 1.27)
			(layers "B.Cu" "B.Mask" "B.Paste")
			(net "GND")
		)
	)
	(footprint ""
		(layer "B.Cu")
		(at 116.84 -86.705948 180)
		(property "Reference" "R4023"
			(at 0 0 0)
			(layer "B.SilkS")
			(hide yes)
			(effects
				(font
					(size 1.27 1.27)
				)
				(justify mirror)
			)
		)
		(property "Value" ""
			(at 0 0 0)
			(layer "B.Fab")
			(effects
				(font
					(size 1.27 1.27)
				)
				(justify mirror)
			)
		)
		(duplicate_pad_numbers_are_jumpers no)
		(fp_line
			(start 0.7874 0.4064)
			(end 0.7874 -0.4064)
			(stroke
				(width 0.1524)
				(type default)
			)
			(layer "B.SilkS")
		)
		(fp_line
			(start 0.7874 -0.4064)
			(end -0.7874 -0.4064)
			(stroke
				(width 0.1524)
				(type default)
			)
			(layer "B.SilkS")
		)
		(fp_line
			(start -0.7874 0.4064)
			(end 0.7874 0.4064)
			(stroke
				(width 0.1524)
				(type default)
			)
			(layer "B.SilkS")
		)
		(fp_line
			(start -0.7874 -0.4064)
			(end -0.7874 0.4064)
			(stroke
				(width 0.1524)
				(type default)
			)
			(layer "B.SilkS")
		)
		(fp_line
			(start 0.67945 0.3048)
			(end 0.67945 -0.305054)
			(stroke
				(width 0.1)
				(type default)
			)
			(layer "B.Fab")
		)
		(fp_line
			(start 0.67945 -0.305054)
			(end 0.12065 -0.305054)
			(stroke
				(width 0.1)
				(type default)
			)
			(layer "B.Fab")
		)
		(fp_line
			(start 0.12065 0.3048)
			(end 0.67945 0.3048)
			(stroke
				(width 0.1)
				(type default)
			)
			(layer "B.Fab")
		)
		(fp_line
			(start 0.12065 0.2794)
			(end 0.12065 0.3048)
			(stroke
				(width 0.1)
				(type default)
			)
			(layer "B.Fab")
		)
		(fp_line
			(start 0.12065 -0.2794)
			(end -0.12065 -0.2794)
			(stroke
				(width 0.1)
				(type default)
			)
			(layer "B.Fab")
		)
		(fp_line
			(start 0.12065 -0.305054)
			(end 0.12065 -0.2794)
			(stroke
				(width 0.1)
				(type default)
			)
			(layer "B.Fab")
		)
		(fp_line
			(start -0.120396 0.3048)
			(end -0.120396 0.2794)
			(stroke
				(width 0.1)
				(type default)
			)
			(layer "B.Fab")
		)
		(fp_line
			(start -0.120396 0.2794)
			(end 0.12065 0.2794)
			(stroke
				(width 0.1)
				(type default)
			)
			(layer "B.Fab")
		)
		(fp_line
			(start -0.12065 -0.2794)
			(end -0.12065 -0.3048)
			(stroke
				(width 0.1)
				(type default)
			)
			(layer "B.Fab")
		)
		(fp_line
			(start -0.12065 -0.3048)
			(end -0.67945 -0.3048)
			(stroke
				(width 0.1)
				(type default)
			)
			(layer "B.Fab")
		)
		(fp_line
			(start -0.67945 0.3048)
			(end -0.120396 0.3048)
			(stroke
				(width 0.1)
				(type default)
			)
			(layer "B.Fab")
		)
		(fp_line
			(start -0.67945 -0.3048)
			(end -0.67945 0.3048)
			(stroke
				(width 0.1)
				(type default)
			)
			(layer "B.Fab")
		)
		(pad "1" smd circle
			(at 0.40005 0)
			(size 0 0)
			(layers "B.Cu" "B.Mask" "B.Paste")
			(net "H_CPU_CATERR_LVC2_R1_N")
		)
		(pad "2" smd circle
			(at -0.40005 0)
			(size 0 0)
			(layers "B.Cu" "B.Mask" "B.Paste")
			(net "H_CPU_CATERR_LVC2_R2_N")
		)
	)
)
